# S9S_MB_2U (Grand Teton) — schematic netlist excerpt (pin names and nets, part order shuffled) for the footprints in the layout excerpt that follows; sources: Cadence DE-HDL packaged netlist, KiCad conversion of 03242023_DA0F0TMBIJ0_F0T_Motherboard_J_brd_V01_OCP.brd

C745  Q_CAP_DIFFBUS  DIFF BUS_0.22UF 6.3V 20% X6S  pkg C0201  page 176 : \1\ = P5E_CPU1_PE2_TX_C_DP<14> ; \2\ = P5E_CPU1_PE2_TX_DP<14>
R4724  Q_RES  100K 1% EMPTY  pkg 0402LF  page 144 : A = PRSNT_SWB_N ; B = GND
PC1653  Q_CAP  100NF 50V 10% X7R  pkg C0402  page 271 : A = P12V_AUX ; B = GND

(kicad_pcb
	(version 20260206)
	(generator "pcbnew")
	(generator_version "10.0")
	(general
		(thickness 1.6)
		(legacy_teardrops no)
	)
	(paper "A4")
	(title_block
		(title "03242023_DA0F0TMBIJ0_F0T_Motherboard_J_brd_V01_OCP.brd")
		(comment 1 "Grand Teton / footprints 2490-2492 of 6105")
	)
	(layers
		(0 "F.Cu" signal "TOP")
		(4 "In1.Cu" signal "GND")
		(6 "In2.Cu" signal "IN1")
		(8 "In3.Cu" signal "GND1")
		(10 "In4.Cu" signal "IN2")
		(12 "In5.Cu" signal "GND2")
		(14 "In6.Cu" signal "IN3")
		(16 "In7.Cu" signal "GND3")
		(18 "In8.Cu" signal "VCC")
		(20 "In9.Cu" signal "VCC1")
		(22 "In10.Cu" signal "GND4")
		(24 "In11.Cu" signal "IN4")
		(26 "In12.Cu" signal "GND5")
		(28 "In13.Cu" signal "IN5")
		(30 "In14.Cu" signal "GND6")
		(32 "In15.Cu" signal "IN6")
		(34 "In16.Cu" signal "GND7")
		(2 "B.Cu" signal "BOTTOM")
		(9 "F.Adhes" user "F.Adhesive")
		(11 "B.Adhes" user "B.Adhesive")
		(13 "F.Paste" user "Package Geometry/Pastemask Top")
		(15 "B.Paste" user "Package Geometry/Pastemask Bottom")
		(5 "F.SilkS" user "Ref Des/Silkscreen Top")
		(7 "B.SilkS" user "Ref Des/Silkscreen Bottom")
		(1 "F.Mask" user "Board Geometry/Soldermask Top")
		(3 "B.Mask" user "Board Geometry/Soldermask Bottom")
		(17 "Dwgs.User" user "User.Drawings")
		(19 "Cmts.User" user "User.Comments")
		(21 "Eco1.User" user "User.Eco1")
		(23 "Eco2.User" user "User.Eco2")
		(25 "Edge.Cuts" user "Board Geometry/Outline")
		(27 "Margin" user)
		(31 "F.CrtYd" user "Package Geometry/Place Bound Top")
		(29 "B.CrtYd" user "Package Geometry/Place Bound Bottom")
		(35 "F.Fab" user "Ref Des/Assembly Top")
		(33 "B.Fab" user "Ref Des/Assembly Bottom")
	)
	(footprint ""
		(layer "F.Cu")
		(at 104.8258 -410.2608 180)
		(property "Reference" "R4724"
			(at 0 0 180)
			(layer "F.SilkS")
			(hide yes)
			(effects
				(font
					(size 1.27 1.27)
				)
			)
		)
		(property "Value" ""
			(at 0 0 180)
			(layer "F.Fab")
			(effects
				(font
					(size 1.27 1.27)
				)
			)
		)
		(duplicate_pad_numbers_are_jumpers no)
		(fp_line
			(start 0.7874 0.4064)
			(end -0.7874 0.4064)
			(stroke
				(width 0.1524)
				(type default)
			)
			(layer "F.SilkS")
		)
		(fp_line
			(start 0.7874 -0.4064)
			(end 0.7874 0.4064)
			(stroke
				(width 0.1524)
				(type default)
			)
			(layer "F.SilkS")
		)
		(fp_line
			(start -0.7874 0.4064)
			(end -0.7874 -0.4064)
			(stroke
				(width 0.1524)
				(type default)
			)
			(layer "F.SilkS")
		)
		(fp_line
			(start -0.7874 -0.4064)
			(end 0.7874 -0.4064)
			(stroke
				(width 0.1524)
				(type default)
			)
			(layer "F.SilkS")
		)
		(fp_line
			(start 0.67945 0.3048)
			(end 0.120396 0.3048)
			(stroke
				(width 0.1)
				(type default)
			)
			(layer "F.Fab")
		)
		(fp_line
			(start 0.67945 -0.3048)
			(end 0.67945 0.3048)
			(stroke
				(width 0.1)
				(type default)
			)
			(layer "F.Fab")
		)
		(fp_line
			(start 0.12065 -0.2794)
			(end 0.12065 -0.3048)
			(stroke
				(width 0.1)
				(type default)
			)
			(layer "F.Fab")
		)
		(fp_line
			(start 0.12065 -0.3048)
			(end 0.67945 -0.3048)
			(stroke
				(width 0.1)
				(type default)
			)
			(layer "F.Fab")
		)
		(fp_line
			(start 0.120396 0.3048)
			(end 0.120396 0.2794)
			(stroke
				(width 0.1)
				(type default)
			)
			(layer "F.Fab")
		)
		(fp_line
			(start 0.120396 0.2794)
			(end -0.12065 0.2794)
			(stroke
				(width 0.1)
				(type default)
			)
			(layer "F.Fab")
		)
		(fp_line
			(start -0.12065 0.3048)
			(end -0.67945 0.3048)
			(stroke
				(width 0.1)
				(type default)
			)
			(layer "F.Fab")
		)
		(fp_line
			(start -0.12065 0.2794)
			(end -0.12065 0.3048)
			(stroke
				(width 0.1)
				(type default)
			)
			(layer "F.Fab")
		)
		(fp_line
			(start -0.12065 -0.2794)
			(end 0.12065 -0.2794)
			(stroke
				(width 0.1)
				(type default)
			)
			(layer "F.Fab")
		)
		(fp_line
			(start -0.12065 -0.305054)
			(end -0.12065 -0.2794)
			(stroke
				(width 0.1)
				(type default)
			)
			(layer "F.Fab")
		)
		(fp_line
			(start -0.67945 0.3048)
			(end -0.67945 -0.305054)
			(stroke
				(width 0.1)
				(type default)
			)
			(layer "F.Fab")
		)
		(fp_line
			(start -0.67945 -0.305054)
			(end -0.12065 -0.305054)
			(stroke
				(width 0.1)
				(type default)
			)
			(layer "F.Fab")
		)
		(pad "1" smd circle
			(at -0.40005 0 180)
			(size 0 0)
			(layers "F.Cu" "F.Mask" "F.Paste")
			(net "PRSNT_SWB_N")
		)
		(pad "2" smd circle
			(at 0.40005 0 180)
			(size 0 0)
			(layers "F.Cu" "F.Mask" "F.Paste")
			(net "GND")
		)
	)
	(footprint ""
		(layer "F.Cu")
		(at 123.192794 -402.371052 -90)
		(property "Reference" "C745"
			(at 0 0 270)
			(layer "F.SilkS")
			(hide yes)
			(effects
				(font
					(size 1.27 1.27)
				)
			)
		)
		(property "Value" ""
			(at 0 0 270)
			(layer "F.Fab")
			(effects
				(font
					(size 1.27 1.27)
				)
			)
		)
		(duplicate_pad_numbers_are_jumpers no)
		(fp_line
			(start -0.299974 0.150114)
			(end -0.299974 -0.150114)
			(stroke
				(width 0.1)
				(type default)
			)
			(layer "F.Fab")
		)
		(fp_line
			(start 0.299974 0.150114)
			(end -0.299974 0.150114)
			(stroke
				(width 0.1)
				(type default)
			)
			(layer "F.Fab")
		)
		(fp_line
			(start -0.299974 -0.150114)
			(end 0.299974 -0.150114)
			(stroke
				(width 0.1)
				(type default)
			)
			(layer "F.Fab")
		)
		(fp_line
			(start 0.299974 -0.150114)
			(end 0.299974 0.150114)
			(stroke
				(width 0.1)
				(type default)
			)
			(layer "F.Fab")
		)
		(pad "1" smd rect
			(at -0.2667 0 270)
			(size 0.3048 0.381)
			(layers "F.Cu" "F.Mask" "F.Paste")
			(net "P5E_CPU1_PE2_TX_C_DP<14>")
		)
		(pad "2" smd rect
			(at 0.2667 0 270)
			(size 0.3048 0.381)
			(layers "F.Cu" "F.Mask" "F.Paste")
			(net "P5E_CPU1_PE2_TX_DP<14>")
		)
	)
	(footprint ""
		(layer "F.Cu")
		(at 290.457382 -375.745502)
		(property "Reference" "PC1653"
			(at 0 0 0)
			(layer "F.SilkS")
			(hide yes)
			(effects
				(font
					(size 1.27 1.27)
				)
			)
		)
		(property "Value" ""
			(at 0 0 0)
			(layer "F.Fab")
			(effects
				(font
					(size 1.27 1.27)
				)
			)
		)
		(duplicate_pad_numbers_are_jumpers no)
		(fp_line
			(start -0.7874 -0.4064)
			(end 0.7874 -0.4064)
			(stroke
				(width 0.1524)
				(type default)
			)
			(layer "F.SilkS")
		)
		(fp_line
			(start -0.7874 0.4064)
			(end -0.7874 -0.4064)
			(stroke
				(width 0.1524)
				(type default)
			)
			(layer "F.SilkS")
		)
		(fp_line
			(start 0.7874 -0.4064)
			(end 0.7874 0.4064)
			(stroke
				(width 0.1524)
				(type default)
			)
			(layer "F.SilkS")
		)
		(fp_line
			(start 0.7874 0.4064)
			(end -0.7874 0.4064)
			(stroke
				(width 0.1524)
				(type default)
			)
			(layer "F.SilkS")
		)
		(fp_line
			(start -0.67945 -0.305054)
			(end -0.12065 -0.305054)
			(stroke
				(width 0.1)
				(type default)
			)
			(layer "F.Fab")
		)
		(fp_line
			(start -0.67945 0.3048)
			(end -0.67945 -0.305054)
			(stroke
				(width 0.1)
				(type default)
			)
			(layer "F.Fab")
		)
		(fp_line
			(start -0.12065 -0.305054)
			(end -0.12065 -0.2794)
			(stroke
				(width 0.1)
				(type default)
			)
			(layer "F.Fab")
		)
		(fp_line
			(start -0.12065 -0.2794)
			(end 0.12065 -0.2794)
			(stroke
				(width 0.1)
				(type default)
			)
			(layer "F.Fab")
		)
		(fp_line
			(start -0.12065 0.2794)
			(end -0.12065 0.3048)
			(stroke
				(width 0.1)
				(type default)
			)
			(layer "F.Fab")
		)
		(fp_line
			(start -0.12065 0.3048)
			(end -0.67945 0.3048)
			(stroke
				(width 0.1)
				(type default)
			)
			(layer "F.Fab")
		)
		(fp_line
			(start 0.120396 0.2794)
			(end -0.12065 0.2794)
			(stroke
				(width 0.1)
				(type default)
			)
			(layer "F.Fab")
		)
		(fp_line
			(start 0.120396 0.3048)
			(end 0.120396 0.2794)
			(stroke
				(width 0.1)
				(type default)
			)
			(layer "F.Fab")
		)
		(fp_line
			(start 0.12065 -0.3048)
			(end 0.67945 -0.3048)
			(stroke
				(width 0.1)
				(type default)
			)
			(layer "F.Fab")
		)
		(fp_line
			(start 0.12065 -0.2794)
			(end 0.12065 -0.3048)
			(stroke
				(width 0.1)
				(type default)
			)
			(layer "F.Fab")
		)
		(fp_line
			(start 0.67945 -0.3048)
			(end 0.67945 0.3048)
			(stroke
				(width 0.1)
				(type default)
			)
			(layer "F.Fab")
		)
		(fp_line
			(start 0.67945 0.3048)
			(end 0.120396 0.3048)
			(stroke
				(width 0.1)
				(type default)
			)
			(layer "F.Fab")
		)
		(pad "1" smd circle
			(at -0.40005 0)
			(size 0 0)
			(layers "F.Cu" "F.Mask" "F.Paste")
			(net "P12V_AUX")
		)
		(pad "2" smd circle
			(at 0.40005 0)
			(size 0 0)
			(layers "F.Cu" "F.Mask" "F.Paste")
			(net "GND")
		)
	)
)
